(kicad_pcb
	(version 20260206)
	(generator "pcbnew")
	(generator_version "10.0")
	(general
		(thickness 1.6)
		(legacy_teardrops no)
	)
	(paper "A4")
	(title_block
		(title "Bryce Canyon_F.DPB_16315-1-OCP.brd")
		(comment 1 "Bryce Canyon / footprints 2034-2039 of 2223")
	)
	(layers
		(0 "F.Cu" signal "TOP")
		(4 "In1.Cu" signal "L2GND")
		(6 "In2.Cu" signal "L3")
		(8 "In3.Cu" signal "L4GND")
		(10 "In4.Cu" signal "L5")
		(12 "In5.Cu" signal "L6VCC")
		(14 "In6.Cu" signal "L7VCC")
		(16 "In7.Cu" signal "L8")
		(18 "In8.Cu" signal "L9GND")
		(20 "In9.Cu" signal "L10")
		(22 "In10.Cu" signal "L11GND")
		(2 "B.Cu" signal "BOTTOM")
		(9 "F.Adhes" user "F.Adhesive")
		(11 "B.Adhes" user "B.Adhesive")
		(13 "F.Paste" user "Package Geometry/Pastemask Top")
		(15 "B.Paste" user "Package Geometry/Pastemask Bottom")
		(5 "F.SilkS" user "Ref Des/Silkscreen Top")
		(7 "B.SilkS" user "Ref Des/Silkscreen Bottom")
		(1 "F.Mask" user "Board Geometry/Soldermask Top")
		(3 "B.Mask" user "Board Geometry/Soldermask Bottom")
		(17 "Dwgs.User" user "User.Drawings")
		(19 "Cmts.User" user "User.Comments")
		(21 "Eco1.User" user "User.Eco1")
		(23 "Eco2.User" user "User.Eco2")
		(25 "Edge.Cuts" user "Board Geometry/Outline")
		(27 "Margin" user)
		(31 "F.CrtYd" user "Package Geometry/Place Bound Top")
		(29 "B.CrtYd" user "Package Geometry/Place Bound Bottom")
		(35 "F.Fab" user "Ref Des/Assembly Top")
		(33 "B.Fab" user "Ref Des/Assembly Bottom")
	)
	(footprint ""
		(layer "F.Cu")
		(at 37.354002 -255.32715)
		(property "Reference" "TP256"
			(at 0 0 0)
			(layer "F.SilkS")
			(hide yes)
			(effects
				(font
					(size 1.27 1.27)
				)
			)
		)
		(property "Value" "TPAD32-GP"
			(at -0.0508 -1.6764 0)
			(unlocked yes)
			(layer "F.Fab")
			(hide yes)
			(effects
				(font
					(size 1.016 1.016)
					(thickness 0.1524)
				)
			)
		)
		(property "Device Type" "TPAD32"
			(at -0.0508 -3.2004 0)
			(unlocked yes)
			(layer "F.Fab")
			(hide yes)
			(effects
				(font
					(size 1.016 1.016)
					(thickness 0.1524)
				)
			)
		)
		(duplicate_pad_numbers_are_jumpers no)
		(fp_poly
			(pts
				(arc
					(start 0.4064 0)
					(mid -0.4064 0)
					(end 0.4064 0)
				)
			)
			(stroke
				(width 0)
				(type default)
			)
			(fill no)
			(layer "F.CrtYd")
		)
		(fp_poly
			(pts
				(arc
					(start 0.7112 0)
					(mid -0.7112 0)
					(end 0.7112 0)
				)
			)
			(stroke
				(width 0)
				(type default)
			)
			(fill no)
			(layer "F.Fab")
		)
		(pad "1" smd circle
			(at 0 0)
			(size 0.8128 0.8128)
			(layers "F.Cu" "F.Mask" "F.Paste")
			(net "P5V_A_1_PGOOD")
		)
	)
	(footprint ""
		(layer "F.Cu")
		(at 139.516866 -131.656074 180)
		(property "Reference" "R1045"
			(at 0 0 180)
			(layer "F.SilkS")
			(hide yes)
			(effects
				(font
					(size 1.27 1.27)
				)
			)
		)
		(property "Value" "10KR2J-3-GP"
			(at 0.064008 -3.993896 180)
			(unlocked yes)
			(layer "F.Fab")
			(hide yes)
			(effects
				(font
					(size 1.016 1.016)
					(thickness 0.1524)
				)
			)
		)
		(property "Device Type" "R402H16"
			(at 0.064008 -5.517896 180)
			(unlocked yes)
			(layer "F.Fab")
			(hide yes)
			(effects
				(font
					(size 1.016 1.016)
					(thickness 0.1524)
				)
			)
		)
		(duplicate_pad_numbers_are_jumpers no)
		(fp_line
			(start 0.508 -0.9398)
			(end -0.508 -0.9398)
			(stroke
				(width 0.1524)
				(type default)
			)
			(layer "F.SilkS")
		)
		(fp_line
			(start -0.508 -0.9398)
			(end -0.508 0.9398)
			(stroke
				(width 0.1524)
				(type default)
			)
			(layer "F.SilkS")
		)
		(fp_rect
			(start -0.508 0.9398)
			(end 0.508 -0.9398)
			(stroke
				(width 0)
				(type default)
			)
			(fill no)
			(layer "F.CrtYd")
		)
		(fp_rect
			(start -0.508 0.9398)
			(end 0.508 -0.9398)
			(stroke
				(width 0)
				(type default)
			)
			(fill no)
			(layer "F.Fab")
		)
		(pad "1" smd custom
			(at 0 -0.4445 180)
			(size 0.1397 0.1397)
			(layers "F.Cu" "F.Mask" "F.Paste")
			(net "GND")
			(options
				(clearance outline)
				(anchor circle)
			)
			(primitives
				(gr_poly
					(pts
						(arc
							(start -0.1778 -0.2794)
							(mid -0.249642 -0.249642)
							(end -0.2794 -0.1778)
						)
						(arc
							(start -0.2794 0.1778)
							(mid -0.249642 0.249642)
							(end -0.1778 0.2794)
						)
						(arc
							(start 0.1778 0.2794)
							(mid 0.249642 0.249642)
							(end 0.2794 0.1778)
						)
						(arc
							(start 0.2794 -0.1778)
							(mid 0.249642 -0.249642)
							(end 0.1778 -0.2794)
						)
					)
					(width 0)
					(fill yes)
				)
			)
		)
		(pad "2" smd custom
			(at 0 0.4445 180)
			(size 0.1397 0.1397)
			(layers "F.Cu" "F.Mask" "F.Paste")
			(net "MB0_RETRY_R")
			(options
				(clearance outline)
				(anchor circle)
			)
			(primitives
				(gr_poly
					(pts
						(arc
							(start -0.1778 -0.2794)
							(mid -0.249642 -0.249642)
							(end -0.2794 -0.1778)
						)
						(arc
							(start -0.2794 0.1778)
							(mid -0.249642 0.249642)
							(end -0.1778 0.2794)
						)
						(arc
							(start 0.1778 0.2794)
							(mid 0.249642 0.249642)
							(end 0.2794 0.1778)
						)
						(arc
							(start 0.2794 -0.1778)
							(mid 0.249642 -0.249642)
							(end 0.1778 -0.2794)
						)
					)
					(width 0)
					(fill yes)
				)
			)
		)
	)
	(footprint ""
		(layer "B.Cu")
		(at 474.542104 -232.678986 180)
		(property "Reference" "U27"
			(at 0 0 0)
			(layer "B.SilkS")
			(hide yes)
			(effects
				(font
					(size 1.27 1.27)
				)
				(justify mirror)
			)
		)
		(property "Value" "TPS53319DQPR-GP"
			(at -4.7498 -5.6896 180)
			(unlocked yes)
			(layer "B.Fab")
			(hide yes)
			(effects
				(font
					(size 1.016 1.016)
					(thickness 0.1524)
				)
				(justify mirror)
			)
		)
		(property "Device Type" "QFN22G6050-G6133H60"
			(at -4.7498 -7.2136 180)
			(unlocked yes)
			(layer "B.Fab")
			(hide yes)
			(effects
				(font
					(size 1.016 1.016)
					(thickness 0.1524)
				)
				(justify mirror)
			)
		)
		(duplicate_pad_numbers_are_jumpers no)
		(fp_line
			(start 3.556 3.5179)
			(end 2.286 3.5179)
			(stroke
				(width 0.1524)
				(type default)
			)
			(layer "B.SilkS")
		)
		(fp_line
			(start 3.556 2.2479)
			(end 3.556 3.5179)
			(stroke
				(width 0.1524)
				(type default)
			)
			(layer "B.SilkS")
		)
		(fp_line
			(start 3.556 -3.5179)
			(end 3.556 -2.2479)
			(stroke
				(width 0.1524)
				(type default)
			)
			(layer "B.SilkS")
		)
		(fp_line
			(start 2.286 -3.5179)
			(end 3.556 -3.5179)
			(stroke
				(width 0.1524)
				(type default)
			)
			(layer "B.SilkS")
		)
		(fp_line
			(start 1.999996 -3.262122)
			(end 1.999996 -4.024122)
			(stroke
				(width 0.1524)
				(type default)
			)
			(layer "B.SilkS")
		)
		(fp_line
			(start 0.999998 3.262122)
			(end 0.999998 3.770122)
			(stroke
				(width 0.1524)
				(type default)
			)
			(layer "B.SilkS")
		)
		(fp_line
			(start -0.500126 -3.262122)
			(end -0.500126 -3.770122)
			(stroke
				(width 0.1524)
				(type default)
			)
			(layer "B.SilkS")
		)
		(fp_line
			(start -1.500124 3.262122)
			(end -1.500124 4.024122)
			(stroke
				(width 0.1524)
				(type default)
			)
			(layer "B.SilkS")
		)
		(fp_line
			(start -2.286 3.5179)
			(end -3.556 3.5179)
			(stroke
				(width 0.1524)
				(type default)
			)
			(layer "B.SilkS")
		)
		(fp_line
			(start -3.556 3.5179)
			(end -3.556 2.2479)
			(stroke
				(width 0.1524)
				(type default)
			)
			(layer "B.SilkS")
		)
		(fp_poly
			(pts
				(xy -3.556 -3.5179) (xy -2.5273 -3.5179) (xy -3.556 -2.4892)
			)
			(stroke
				(width 0)
				(type default)
			)
			(fill yes)
			(layer "B.SilkS")
		)
		(fp_rect
			(start 2.9972 2.5019)
			(end -2.9972 -2.5019)
			(stroke
				(width 0)
				(type default)
			)
			(fill no)
			(layer "B.CrtYd")
		)
		(fp_poly
			(pts
				(xy -3.556 -2.5019) (xy 2.9972 -2.5019) (xy 2.9972 2.5019) (xy -2.9972 2.5019) (xy -2.9972 -2.4892)
				(xy -3.556 -2.4892) (xy -3.556 3.5179) (xy 3.556 3.5179) (xy 3.556 -3.5179) (xy -3.556 -3.5179)
			)
			(stroke
				(width 0)
				(type default)
			)
			(fill no)
			(layer "B.CrtYd")
		)
		(fp_rect
			(start 3.556 3.5179)
			(end -3.556 -3.5179)
			(stroke
				(width 0)
				(type default)
			)
			(fill no)
			(layer "B.Fab")
		)
		(pad "1" smd rect
			(at -2.500122 -2.449322)
			(size 0.3048 1.1176)
			(layers "B.Cu" "B.Mask" "B.Paste")
			(net "P5V_D_VFB")
		)
		(pad "2" smd rect
			(at -1.999996 -2.449322)
			(size 0.3048 1.1176)
			(layers "B.Cu" "B.Mask" "B.Paste")
			(net "P5V_D_EN_R")
		)
		(pad "3" smd rect
			(at -1.500124 -2.449322)
			(size 0.3048 1.1176)
			(layers "B.Cu" "B.Mask" "B.Paste")
			(net "P5V_A_4_PGOOD")
		)
		(pad "4" smd rect
			(at -0.999998 -2.449322)
			(size 0.3048 1.1176)
			(layers "B.Cu" "B.Mask" "B.Paste")
			(net "P5V_D_VBST")
		)
		(pad "5" smd rect
			(at -0.500126 -2.449322)
			(size 0.3048 1.1176)
			(layers "B.Cu" "B.Mask" "B.Paste")
			(net "P5V_D_ROVP")
		)
		(pad "6" smd rect
			(at 0 -2.449322)
			(size 0.3048 1.1176)
			(layers "B.Cu" "B.Mask" "B.Paste")
			(net "P5V_D_LL")
		)
		(pad "7" smd rect
			(at 0.500126 -2.449322)
			(size 0.3048 1.1176)
			(layers "B.Cu" "B.Mask" "B.Paste")
			(net "P5V_D_LL")
		)
		(pad "8" smd rect
			(at 0.999998 -2.449322)
			(size 0.3048 1.1176)
			(layers "B.Cu" "B.Mask" "B.Paste")
			(net "P5V_D_LL")
		)
		(pad "9" smd rect
			(at 1.500124 -2.449322)
			(size 0.3048 1.1176)
			(layers "B.Cu" "B.Mask" "B.Paste")
			(net "P5V_D_LL")
		)
		(pad "10" smd rect
			(at 1.999996 -2.449322)
			(size 0.3048 1.1176)
			(layers "B.Cu" "B.Mask" "B.Paste")
			(net "P5V_D_LL")
		)
		(pad "11" smd rect
			(at 2.500122 -2.449322)
			(size 0.3048 1.1176)
			(layers "B.Cu" "B.Mask" "B.Paste")
			(net "P5V_D_LL")
		)
		(pad "12" smd rect
			(at 2.500122 2.449322)
			(size 0.3048 1.1176)
			(layers "B.Cu" "B.Mask" "B.Paste")
			(net "P12V_A_VIN_U27")
		)
		(pad "13" smd rect
			(at 1.999996 2.449322)
			(size 0.3048 1.1176)
			(layers "B.Cu" "B.Mask" "B.Paste")
			(net "P12V_A_VIN_U27")
		)
		(pad "14" smd rect
			(at 1.500124 2.449322)
			(size 0.3048 1.1176)
			(layers "B.Cu" "B.Mask" "B.Paste")
			(net "P12V_A_VIN_U27")
		)
		(pad "15" smd rect
			(at 0.999998 2.449322)
			(size 0.3048 1.1176)
			(layers "B.Cu" "B.Mask" "B.Paste")
			(net "P12V_A_VIN_U27")
		)
		(pad "16" smd rect
			(at 0.500126 2.449322)
			(size 0.3048 1.1176)
			(layers "B.Cu" "B.Mask" "B.Paste")
			(net "P12V_A_VIN_U27")
		)
		(pad "17" smd rect
			(at 0 2.449322)
			(size 0.3048 1.1176)
			(layers "B.Cu" "B.Mask" "B.Paste")
			(net "P12V_A_VIN_U27")
		)
		(pad "18" smd rect
			(at -0.500126 2.449322)
			(size 0.3048 1.1176)
			(layers "B.Cu" "B.Mask" "B.Paste")
			(net "P5V_D_VREG")
		)
		(pad "19" smd rect
			(at -0.999998 2.449322)
			(size 0.3048 1.1176)
			(layers "B.Cu" "B.Mask" "B.Paste")
			(net "P12V_A_VDD_U27")
		)
		(pad "20" smd rect
			(at -1.500124 2.449322)
			(size 0.3048 1.1176)
			(layers "B.Cu" "B.Mask" "B.Paste")
			(net "P5V_D_MODE")
		)
		(pad "21" smd rect
			(at -1.999996 2.449322)
			(size 0.3048 1.1176)
			(layers "B.Cu" "B.Mask" "B.Paste")
			(net "P5V_D_TRIP")
		)
		(pad "22" smd rect
			(at -2.500122 2.449322)
			(size 0.3048 1.1176)
			(layers "B.Cu" "B.Mask" "B.Paste")
			(net "P5V_D_RF")
		)
		(pad "23" smd custom
			(at 0 0)
			(size 0.83185 0.83185)
			(layers "B.Cu" "B.Mask" "B.Paste")
			(net "GND")
			(options
				(clearance outline)
				(anchor circle)
			)
			(primitives
				(gr_poly
					(pts
						(xy -2.7813 -1.6637) (xy -2.7813 -1.2954) (xy -3.048 -1.2954) (xy -3.048 -0.9525) (xy -2.7813 -0.9525)
						(xy -2.7813 0.9525) (xy -3.048 0.9525) (xy -3.048 1.2954) (xy -2.7813 1.2954) (xy -2.7813 1.6637)
						(xy 2.7813 1.6637) (xy 2.7813 1.2954) (xy 3.048 1.2954) (xy 3.048 0.9525) (xy 2.7813 0.9525) (xy 2.7813 -0.9525)
						(xy 3.048 -0.9525) (xy 3.048 -1.2954) (xy 2.7813 -1.2954) (xy 2.7813 -1.6637)
					)
					(width 0)
					(fill yes)
				)
			)
		)
	)
	(footprint ""
		(layer "B.Cu")
		(at 216.535 -123.4948 180)
		(property "Reference" "R355"
			(at 0 0 0)
			(layer "B.SilkS")
			(hide yes)
			(effects
				(font
					(size 1.27 1.27)
				)
				(justify mirror)
			)
		)
		(property "Value" "0R2J-2-GP"
			(at -0.064008 -3.993896 180)
			(unlocked yes)
			(layer "B.Fab")
			(hide yes)
			(effects
				(font
					(size 1.016 1.016)
					(thickness 0.1524)
				)
				(justify mirror)
			)
		)
		(property "Device Type" "R402H16"
			(at -0.064008 -5.517896 180)
			(unlocked yes)
			(layer "B.Fab")
			(hide yes)
			(effects
				(font
					(size 1.016 1.016)
					(thickness 0.1524)
				)
				(justify mirror)
			)
		)
		(duplicate_pad_numbers_are_jumpers no)
		(fp_line
			(start 0.508 -0.9398)
			(end 0.508 0.9398)
			(stroke
				(width 0.1524)
				(type default)
			)
			(layer "B.SilkS")
		)
		(fp_line
			(start -0.508 -0.9398)
			(end 0.508 -0.9398)
			(stroke
				(width 0.1524)
				(type default)
			)
			(layer "B.SilkS")
		)
		(fp_rect
			(start 0.508 0.9398)
			(end -0.508 -0.9398)
			(stroke
				(width 0)
				(type default)
			)
			(fill no)
			(layer "B.CrtYd")
		)
		(fp_rect
			(start 0.508 0.9398)
			(end -0.508 -0.9398)
			(stroke
				(width 0)
				(type default)
			)
			(fill no)
			(layer "B.Fab")
		)
		(pad "1" smd custom
			(at 0 -0.4445)
			(size 0.1397 0.1397)
			(layers "B.Cu" "B.Mask" "B.Paste")
			(net "I2C_BMC_A_COMP_A_SDA")
			(options
				(clearance outline)
				(anchor circle)
			)
			(primitives
				(gr_poly
					(pts
						(arc
							(start -0.1778 0.2794)
							(mid -0.249642 0.249642)
							(end -0.2794 0.1778)
						)
						(arc
							(start -0.2794 -0.1778)
							(mid -0.249642 -0.249642)
							(end -0.1778 -0.2794)
						)
						(arc
							(start 0.1778 -0.2794)
							(mid 0.249642 -0.249642)
							(end 0.2794 -0.1778)
						)
						(arc
							(start 0.2794 0.1778)
							(mid 0.249642 0.249642)
							(end 0.1778 0.2794)
						)
					)
					(width 0)
					(fill yes)
				)
			)
		)
		(pad "2" smd custom
			(at 0 0.4445)
			(size 0.1397 0.1397)
			(layers "B.Cu" "B.Mask" "B.Paste")
			(net "I2C_BMC_A_COMP_A_SDA_R")
			(options
				(clearance outline)
				(anchor circle)
			)
			(primitives
				(gr_poly
					(pts
						(arc
							(start -0.1778 0.2794)
							(mid -0.249642 0.249642)
							(end -0.2794 0.1778)
						)
						(arc
							(start -0.2794 -0.1778)
							(mid -0.249642 -0.249642)
							(end -0.1778 -0.2794)
						)
						(arc
							(start 0.1778 -0.2794)
							(mid 0.249642 -0.249642)
							(end 0.2794 -0.1778)
						)
						(arc
							(start 0.2794 0.1778)
							(mid 0.249642 0.249642)
							(end 0.1778 0.2794)
						)
					)
					(width 0)
					(fill yes)
				)
			)
		)
	)
	(footprint ""
		(layer "B.Cu")
		(at 37.084 -142.1384 180)
		(property "Reference" "C618"
			(at 0 0 0)
			(layer "B.SilkS")
			(hide yes)
			(effects
				(font
					(size 1.27 1.27)
				)
				(justify mirror)
			)
		)
		(property "Value" "SC10U16V5KX-7-GP-U"
			(at 0.0762 -6.1214 180)
			(unlocked yes)
			(layer "B.Fab")
			(hide yes)
			(effects
				(font
					(size 1.016 1.016)
					(thickness 0.1524)
				)
				(justify mirror)
			)
		)
		(property "Device Type" "C805H58"
			(at 0.0762 -8.1534 180)
			(unlocked yes)
			(layer "B.Fab")
			(hide yes)
			(effects
				(font
					(size 1.016 1.016)
					(thickness 0.1524)
				)
				(justify mirror)
			)
		)
		(duplicate_pad_numbers_are_jumpers no)
		(fp_line
			(start -0.635 0)
			(end 0.635 0)
			(stroke
				(width 0.508)
				(type default)
			)
			(layer "B.SilkS")
		)
		(fp_rect
			(start 0.9652 1.778)
			(end -0.9652 -1.778)
			(stroke
				(width 0)
				(type default)
			)
			(fill no)
			(layer "B.CrtYd")
		)
		(fp_poly
			(pts
				(xy 0.9652 -1.778) (xy -0.9652 -1.778) (xy -0.9652 1.778) (xy 0.9652 1.778)
			)
			(stroke
				(width 0)
				(type default)
			)
			(fill no)
			(layer "B.Fab")
		)
		(pad "1" smd rect
			(at 0 -0.9652)
			(size 1.397 1.143)
			(layers "B.Cu" "B.Mask" "B.Paste")
			(net "P12V_A_VIN_U21")
		)
		(pad "2" smd rect
			(at 0 0.9652)
			(size 1.397 1.143)
			(layers "B.Cu" "B.Mask" "B.Paste")
			(net "GND")
		)
	)
	(footprint ""
		(layer "B.Cu")
		(at 32.3342 -253.4158 90)
		(property "Reference" "R1217"
			(at 0 0 90)
			(layer "B.SilkS")
			(hide yes)
			(effects
				(font
					(size 1.27 1.27)
				)
				(justify mirror)
			)
		)
		(property "Value" "71K5R2F-GP"
			(at -0.064008 -3.993896 90)
			(unlocked yes)
			(layer "B.Fab")
			(hide yes)
			(effects
				(font
					(size 1.016 1.016)
					(thickness 0.1524)
				)
				(justify mirror)
			)
		)
		(property "Device Type" "R402H16"
			(at -0.064008 -5.517896 90)
			(unlocked yes)
			(layer "B.Fab")
			(hide yes)
			(effects
				(font
					(size 1.016 1.016)
					(thickness 0.1524)
				)
				(justify mirror)
			)
		)
		(duplicate_pad_numbers_are_jumpers no)
		(fp_line
			(start 0.508 -0.9398)
			(end 0.508 0.9398)
			(stroke
				(width 0.1524)
				(type default)
			)
			(layer "B.SilkS")
		)
		(fp_line
			(start -0.508 -0.9398)
			(end 0.508 -0.9398)
			(stroke
				(width 0.1524)
				(type default)
			)
			(layer "B.SilkS")
		)
		(fp_rect
			(start 0.508 0.9398)
			(end -0.508 -0.9398)
			(stroke
				(width 0)
				(type default)
			)
			(fill no)
			(layer "B.CrtYd")
		)
		(fp_rect
			(start 0.508 0.9398)
			(end -0.508 -0.9398)
			(stroke
				(width 0)
				(type default)
			)
			(fill no)
			(layer "B.Fab")
		)
		(pad "1" smd custom
			(at 0 -0.4445 270)
			(size 0.1397 0.1397)
			(layers "B.Cu" "B.Mask" "B.Paste")
			(net "P5V_A_VFB")
			(options
				(clearance outline)
				(anchor circle)
			)
			(primitives
				(gr_poly
					(pts
						(arc
							(start -0.1778 0.2794)
							(mid -0.249642 0.249642)
							(end -0.2794 0.1778)
						)
						(arc
							(start -0.2794 -0.1778)
							(mid -0.249642 -0.249642)
							(end -0.1778 -0.2794)
						)
						(arc
							(start 0.1778 -0.2794)
							(mid 0.249642 -0.249642)
							(end 0.2794 -0.1778)
						)
						(arc
							(start 0.2794 0.1778)
							(mid 0.249642 0.249642)
							(end 0.1778 0.2794)
						)
					)
					(width 0)
					(fill yes)
				)
			)
		)
		(pad "2" smd custom
			(at 0 0.4445 270)
			(size 0.1397 0.1397)
			(layers "B.Cu" "B.Mask" "B.Paste")
			(net "P5V_A_VFB_R")
			(options
				(clearance outline)
				(anchor circle)
			)
			(primitives
				(gr_poly
					(pts
						(arc
							(start -0.1778 0.2794)
							(mid -0.249642 0.249642)
							(end -0.2794 0.1778)
						)
						(arc
							(start -0.2794 -0.1778)
							(mid -0.249642 -0.249642)
							(end -0.1778 -0.2794)
						)
						(arc
							(start 0.1778 -0.2794)
							(mid 0.249642 -0.249642)
							(end 0.2794 -0.1778)
						)
						(arc
							(start 0.2794 0.1778)
							(mid 0.249642 0.249642)
							(end 0.1778 0.2794)
						)
					)
					(width 0)
					(fill yes)
				)
			)
		)
	)
)
